(lib_symbols
	(symbol "antmicroCapacitors0402:C_100n_16V_X7R_0402"
			(pin_numbers
				(hide yes)
			)
			(pin_names
				(hide yes)
			)
			(exclude_from_sim no)
			(in_bom yes)
			(on_board yes)
			(property "Reference" "C"
				(at 15.24 -5.08 0)
				(effects
					(font
						(size 1.27 1.27)
						(thickness 0.15)
					)
					(justify left bottom)
				)
			)
			(property "Value" "C_100n_16V_X7R_0402"
				(at 15.24 -22.86 0)
				(effects
					(font
						(size 1.27 1.27)
						(thickness 0.15)
					)
					(justify left bottom)
					(hide yes)
				)
			)
			(property "Footprint" "antmicro-footprints:C_0402_1005Metric"
				(at 15.24 -25.4 0)
				(effects
					(font
						(size 1.27 1.27)
						(thickness 0.15)
					)
					(justify left bottom)
					(hide yes)
				)
			)
			(property "Datasheet" "https://www.kemet.com/en/us/capacitors/product/C0402C104J4RAC7411.html"
				(at 15.24 -27.94 0)
				(effects
					(font
						(size 1.27 1.27)
						(thickness 0.15)
					)
					(justify left bottom)
					(hide yes)
				)
			)
			(property "Description" "SMD Multilayer Ceramic Capacitor, 100nF, 50V, 0402, ±5%, X7R"
				(at 15.24 -33.02 0)
				(effects
					(font
						(size 1.27 1.27)
					)
					(justify left bottom)
					(hide yes)
				)
			)
			(property "MPN" "C0402C104J4RAC7411"
				(at 15.24 -30.48 0)
				(effects
					(font
						(size 1.27 1.27)
						(thickness 0.15)
					)
					(justify left bottom)
					(hide yes)
				)
			)
			(property "Val" "100n"
				(at 15.24 -7.62 0)
				(effects
					(font
						(size 1.27 1.27)
						(thickness 0.15)
					)
					(justify left bottom)
				)
			)
			(property "Voltage" "16V"
				(at 15.24 -10.16 0)
				(effects
					(font
						(size 1.27 1.27)
						(thickness 0.15)
					)
					(justify left bottom)
					(hide yes)
				)
			)
			(property "Dielectric" "X7R"
				(at 15.24 -12.7 0)
				(effects
					(font
						(size 1.27 1.27)
						(thickness 0.15)
					)
					(justify left bottom)
					(hide yes)
				)
			)
			(property "Manufacturer" "KEMET"
				(at 15.24 -15.24 0)
				(effects
					(font
						(size 1.27 1.27)
						(thickness 0.15)
					)
					(justify left bottom)
					(hide yes)
				)
			)
			(property "License" "Apache-2.0"
				(at 15.24 -17.78 0)
				(effects
					(font
						(size 1.27 1.27)
						(thickness 0.15)
					)
					(justify left bottom)
					(hide yes)
				)
			)
			(property "Author" "Antmicro"
				(at 15.24 -20.32 0)
				(effects
					(font
						(size 1.27 1.27)
						(thickness 0.15)
					)
					(justify left bottom)
					(hide yes)
				)
			)
			(property "ki_keywords" "SMT, CAPACITOR, PASSIVE"
				(at 0 0 0)
				(effects
					(font
						(size 1.27 1.27)
					)
					(hide yes)
				)
			)
			(symbol "C_100n_16V_X7R_0402_0_1"
				(polyline
					(pts
						(xy 2.032 -1.524) (xy 2.032 1.524)
					)
					(stroke
						(width 0.3048)
						(type default)
					)
					(fill
						(type none)
					)
				)
				(polyline
					(pts
						(xy 3.048 -1.524) (xy 3.048 1.524)
					)
					(stroke
						(width 0.3302)
						(type default)
					)
					(fill
						(type none)
					)
				)
			)
			(symbol "C_100n_16V_X7R_0402_1_1"
				(pin passive line
					(at 0 0 0)
					(length 2.032)
					(name "~"
						(effects
							(font
								(size 1.27 1.27)
							)
						)
					)
					(number "1"
						(effects
							(font
								(size 1.27 1.27)
							)
						)
					)
				)
				(pin passive line
					(at 5.08 0 180)
					(length 2.032)
					(name "~"
						(effects
							(font
								(size 1.27 1.27)
							)
						)
					)
					(number "2"
						(effects
							(font
								(size 1.27 1.27)
							)
						)
					)
				)
			)
		)
	(symbol "antmicroCapacitors0603:C_1u_0603"
			(pin_numbers
				(hide yes)
			)
			(pin_names
				(hide yes)
			)
			(exclude_from_sim no)
			(in_bom yes)
			(on_board yes)
			(property "Reference" "C"
				(at 20.32 -5.08 0)
				(effects
					(font
						(size 1.27 1.27)
						(thickness 0.15)
					)
					(justify left bottom)
				)
			)
			(property "Value" "C_1u_0603"
				(at 20.32 -10.16 0)
				(effects
					(font
						(size 1.27 1.27)
						(thickness 0.15)
					)
					(justify left bottom)
					(hide yes)
				)
			)
			(property "Footprint" "antmicro-footprints:C_0603_1608Metric"
				(at 20.32 -12.7 0)
				(effects
					(font
						(size 1.27 1.27)
						(thickness 0.15)
					)
					(justify left bottom)
					(hide yes)
				)
			)
			(property "Datasheet" "https://spicat.kyocera-avx.com/product/mlcc/chartview/0603YD105KAT2A/"
				(at 20.32 -15.24 0)
				(effects
					(font
						(size 1.27 1.27)
						(thickness 0.15)
					)
					(justify left bottom)
					(hide yes)
				)
			)
			(property "Description" "SMD Multilayer Ceramic Capacitor, 1 µF, 16 V, 0603 [1608 Metric], ± 10%, X5R, AVX 0603 MLCC"
				(at 20.32 -33.02 0)
				(effects
					(font
						(size 1.27 1.27)
					)
					(justify left bottom)
					(hide yes)
				)
			)
			(property "MPN" "0603YD105KAT2A"
				(at 20.32 -17.78 0)
				(effects
					(font
						(size 1.27 1.27)
						(thickness 0.15)
					)
					(justify left bottom)
					(hide yes)
				)
			)
			(property "Manufacturer" "KYOCERA AVX"
				(at 20.32 -20.32 0)
				(effects
					(font
						(size 1.27 1.27)
						(thickness 0.15)
					)
					(justify left bottom)
					(hide yes)
				)
			)
			(property "License" "Apache-2.0"
				(at 20.32 -22.86 0)
				(effects
					(font
						(size 1.27 1.27)
						(thickness 0.15)
					)
					(justify left bottom)
					(hide yes)
				)
			)
			(property "Author" "Antmicro"
				(at 20.32 -25.4 0)
				(effects
					(font
						(size 1.27 1.27)
						(thickness 0.15)
					)
					(justify left bottom)
					(hide yes)
				)
			)
			(property "Val" "1u"
				(at 20.32 -7.62 0)
				(effects
					(font
						(size 1.27 1.27)
						(thickness 0.15)
					)
					(justify left bottom)
				)
			)
			(property "Voltage" ""
				(at 20.32 -27.94 0)
				(effects
					(font
						(size 1.27 1.27)
					)
					(justify left bottom)
					(hide yes)
				)
			)
			(property "Dielectric" ""
				(at 20.32 -30.48 0)
				(effects
					(font
						(size 1.27 1.27)
					)
					(justify left bottom)
					(hide yes)
				)
			)
			(property "ki_keywords" "0603, SMT, CAPACITOR, PASSIVE, MLCC"
				(at 0 0 0)
				(effects
					(font
						(size 1.27 1.27)
					)
					(hide yes)
				)
			)
			(symbol "C_1u_0603_0_1"
				(polyline
					(pts
						(xy 2.032 -1.524) (xy 2.032 1.524)
					)
					(stroke
						(width 0.3048)
						(type default)
					)
					(fill
						(type none)
					)
				)
				(polyline
					(pts
						(xy 3.048 -1.524) (xy 3.048 1.524)
					)
					(stroke
						(width 0.3302)
						(type default)
					)
					(fill
						(type none)
					)
				)
			)
			(symbol "C_1u_0603_1_1"
				(pin passive line
					(at 0 0 0)
					(length 2.032)
					(name "~"
						(effects
							(font
								(size 1.27 1.27)
							)
						)
					)
					(number "1"
						(effects
							(font
								(size 1.27 1.27)
							)
						)
					)
				)
				(pin passive line
					(at 5.08 0 180)
					(length 2.032)
					(name "~"
						(effects
							(font
								(size 1.27 1.27)
							)
						)
					)
					(number "2"
						(effects
							(font
								(size 1.27 1.27)
							)
						)
					)
				)
			)
		)
	(symbol "antmicroEdgeConnectors:PCB-Edge_M.2_Key-M"
			(exclude_from_sim no)
			(in_bom no)
			(on_board yes)
			(property "Reference" "J"
				(at 53.34 -2.54 0)
				(effects
					(font
						(size 1.27 1.27)
						(thickness 0.15)
					)
					(justify left bottom)
				)
			)
			(property "Value" "PCB-Edge_M.2_Key-M"
				(at 53.34 -5.08 0)
				(effects
					(font
						(size 1.27 1.27)
						(thickness 0.15)
					)
					(justify left bottom)
				)
			)
			(property "Footprint" "antmicro-footprints:PCB-Edge_M.2_Key-M"
				(at 53.34 -7.62 0)
				(effects
					(font
						(size 1.27 1.27)
						(thickness 0.15)
					)
					(justify left bottom)
					(hide yes)
				)
			)
			(property "Datasheet" "https://www.amphenol-icc.com/media/wysiwyg/files/drawing/10130618.pdf"
				(at 53.34 -10.16 0)
				(effects
					(font
						(size 1.27 1.27)
						(thickness 0.15)
					)
					(justify left bottom)
					(hide yes)
				)
			)
			(property "Description" "PCB Edge for M.2 key M"
				(at 53.34 -17.78 0)
				(effects
					(font
						(size 1.27 1.27)
					)
					(justify left bottom)
					(hide yes)
				)
			)
			(property "Author" "Antmicro"
				(at 53.34 -12.7 0)
				(effects
					(font
						(size 1.27 1.27)
						(thickness 0.15)
					)
					(justify left bottom)
					(hide yes)
				)
			)
			(property "License" "Apache-2.0"
				(at 53.34 -15.24 0)
				(effects
					(font
						(size 1.27 1.27)
						(thickness 0.15)
					)
					(justify left bottom)
					(hide yes)
				)
			)
			(property "ki_keywords" "PCB, EDGE, M.2"
				(at 0 0 0)
				(effects
					(font
						(size 1.27 1.27)
					)
					(hide yes)
				)
			)
			(symbol "PCB-Edge_M.2_Key-M_1_1"
				(rectangle
					(start 2.54 2.54)
					(end 35.56 -63.5)
					(stroke
						(width 0.254)
						(type solid)
					)
					(fill
						(type background)
					)
				)
				(text "M.2 Mechanical Key M"
					(at 7.62 -1.27 0)
					(effects
						(font
							(size 1.27 1.27)
							(thickness 0.15)
						)
						(justify left bottom)
					)
				)
				(pin power_in line
					(at 0 0 0)
					(length 2.54)
					(name "3.3V"
						(effects
							(font
								(size 1.27 1.27)
							)
						)
					)
					(number "12"
						(effects
							(font
								(size 1.27 1.27)
							)
						)
					)
				)
				(pin passive line
					(at 0 0 0)
					(length 2.54)
					(hide yes)
					(name "3.3V"
						(effects
							(font
								(size 1.27 1.27)
							)
						)
					)
					(number "14"
						(effects
							(font
								(size 1.27 1.27)
							)
						)
					)
				)
				(pin passive line
					(at 0 0 0)
					(length 2.54)
					(hide yes)
					(name "3.3V"
						(effects
							(font
								(size 1.27 1.27)
							)
						)
					)
					(number "16"
						(effects
							(font
								(size 1.27 1.27)
							)
						)
					)
				)
				(pin passive line
					(at 0 0 0)
					(length 2.54)
					(hide yes)
					(name "3.3V"
						(effects
							(font
								(size 1.27 1.27)
							)
						)
					)
					(number "18"
						(effects
							(font
								(size 1.27 1.27)
							)
						)
					)
				)
				(pin passive line
					(at 0 0 0)
					(length 2.54)
					(hide yes)
					(name "3.3V"
						(effects
							(font
								(size 1.27 1.27)
							)
						)
					)
					(number "2"
						(effects
							(font
								(size 1.27 1.27)
							)
						)
					)
				)
				(pin passive line
					(at 0 0 0)
					(length 2.54)
					(hide yes)
					(name "3.3V"
						(effects
							(font
								(size 1.27 1.27)
							)
						)
					)
					(number "4"
						(effects
							(font
								(size 1.27 1.27)
							)
						)
					)
				)
				(pin passive line
					(at 0 0 0)
					(length 2.54)
					(hide yes)
					(name "3.3V"
						(effects
							(font
								(size 1.27 1.27)
							)
						)
					)
					(number "70"
						(effects
							(font
								(size 1.27 1.27)
							)
						)
					)
				)
				(pin passive line
					(at 0 0 0)
					(length 2.54)
					(hide yes)
					(name "3.3V"
						(effects
							(font
								(size 1.27 1.27)
							)
						)
					)
					(number "72"
						(effects
							(font
								(size 1.27 1.27)
							)
						)
					)
				)
				(pin passive line
					(at 0 0 0)
					(length 2.54)
					(hide yes)
					(name "3.3V"
						(effects
							(font
								(size 1.27 1.27)
							)
						)
					)
					(number "74"
						(effects
							(font
								(size 1.27 1.27)
							)
						)
					)
				)
				(pin passive line
					(at 0 -3.81 0)
					(length 2.54)
					(name "PERp3"
						(effects
							(font
								(size 1.27 1.27)
							)
						)
					)
					(number "7"
						(effects
							(font
								(size 1.27 1.27)
							)
						)
					)
				)
				(pin passive line
					(at 0 -6.35 0)
					(length 2.54)
					(name "PERn3"
						(effects
							(font
								(size 1.27 1.27)
							)
						)
					)
					(number "5"
						(effects
							(font
								(size 1.27 1.27)
							)
						)
					)
				)
				(pin passive line
					(at 0 -10.16 0)
					(length 2.54)
					(name "PETp3"
						(effects
							(font
								(size 1.27 1.27)
							)
						)
					)
					(number "13"
						(effects
							(font
								(size 1.27 1.27)
							)
						)
					)
				)
				(pin passive line
					(at 0 -12.7 0)
					(length 2.54)
					(name "PETn3"
						(effects
							(font
								(size 1.27 1.27)
							)
						)
					)
					(number "11"
						(effects
							(font
								(size 1.27 1.27)
							)
						)
					)
				)
				(pin passive line
					(at 0 -16.51 0)
					(length 2.54)
					(name "PERp2"
						(effects
							(font
								(size 1.27 1.27)
							)
						)
					)
					(number "19"
						(effects
							(font
								(size 1.27 1.27)
							)
						)
					)
				)
				(pin passive line
					(at 0 -19.05 0)
					(length 2.54)
					(name "PERn2"
						(effects
							(font
								(size 1.27 1.27)
							)
						)
					)
					(number "17"
						(effects
							(font
								(size 1.27 1.27)
							)
						)
					)
				)
				(pin passive line
					(at 0 -22.86 0)
					(length 2.54)
					(name "PETp2"
						(effects
							(font
								(size 1.27 1.27)
							)
						)
					)
					(number "25"
						(effects
							(font
								(size 1.27 1.27)
							)
						)
					)
				)
				(pin passive line
					(at 0 -25.4 0)
					(length 2.54)
					(name "PETn2"
						(effects
							(font
								(size 1.27 1.27)
							)
						)
					)
					(number "23"
						(effects
							(font
								(size 1.27 1.27)
							)
						)
					)
				)
				(pin passive line
					(at 0 -29.21 0)
					(length 2.54)
					(name "PERp1"
						(effects
							(font
								(size 1.27 1.27)
							)
						)
					)
					(number "31"
						(effects
							(font
								(size 1.27 1.27)
							)
						)
					)
				)
				(pin passive line
					(at 0 -31.75 0)
					(length 2.54)
					(name "PERn1"
						(effects
							(font
								(size 1.27 1.27)
							)
						)
					)
					(number "29"
						(effects
							(font
								(size 1.27 1.27)
							)
						)
					)
				)
				(pin passive line
					(at 0 -35.56 0)
					(length 2.54)
					(name "PETp1"
						(effects
							(font
								(size 1.27 1.27)
							)
						)
					)
					(number "37"
						(effects
							(font
								(size 1.27 1.27)
							)
						)
					)
				)
				(pin passive line
					(at 0 -38.1 0)
					(length 2.54)
					(name "PETn1"
						(effects
							(font
								(size 1.27 1.27)
							)
						)
					)
					(number "35"
						(effects
							(font
								(size 1.27 1.27)
							)
						)
					)
				)
				(pin passive line
					(at 0 -41.91 0)
					(length 2.54)
					(name "SATA-B+"
						(effects
							(font
								(size 1.27 1.27)
							)
						)
					)
					(number "43"
						(effects
							(font
								(size 1.27 1.27)
							)
						)
					)
					(alternate "PERp0" passive line)
				)
				(pin passive line
					(at 0 -44.45 0)
					(length 2.54)
					(name "SATA-B-"
						(effects
							(font
								(size 1.27 1.27)
							)
						)
					)
					(number "41"
						(effects
							(font
								(size 1.27 1.27)
							)
						)
					)
					(alternate "PERn0" passive line)
				)
				(pin passive line
					(at 0 -48.26 0)
					(length 2.54)
					(name "SATA-A+"
						(effects
							(font
								(size 1.27 1.27)
							)
						)
					)
					(number "49"
						(effects
							(font
								(size 1.27 1.27)
							)
						)
					)
					(alternate "PETp0" passive line)
				)
				(pin passive line
					(at 0 -50.8 0)
					(length 2.54)
					(name "SATA-A-"
						(effects
							(font
								(size 1.27 1.27)
							)
						)
					)
					(number "47"
						(effects
							(font
								(size 1.27 1.27)
							)
						)
					)
					(alternate "PETn0" passive line)
				)
				(pin passive line
					(at 0 -54.61 0)
					(length 2.54)
					(name "REFCLKp"
						(effects
							(font
								(size 1.27 1.27)
							)
						)
					)
					(number "55"
						(effects
							(font
								(size 1.27 1.27)
							)
						)
					)
				)
				(pin passive line
					(at 0 -57.15 0)
					(length 2.54)
					(name "REFCLKn"
						(effects
							(font
								(size 1.27 1.27)
							)
						)
					)
					(number "53"
						(effects
							(font
								(size 1.27 1.27)
							)
						)
					)
				)
				(pin passive line
					(at 0 -60.96 0)
					(length 2.54)
					(name "PEDET"
						(effects
							(font
								(size 1.27 1.27)
							)
						)
					)
					(number "69"
						(effects
							(font
								(size 1.27 1.27)
							)
						)
					)
				)
				(pin no_connect line
					(at 35.56 -15.24 180)
					(length 2.54)
					(hide yes)
					(name "NC"
						(effects
							(font
								(size 1.27 1.27)
							)
						)
					)
					(number "67"
						(effects
							(font
								(size 1.27 1.27)
							)
						)
					)
					(alternate "A" passive line)
				)
				(pin no_connect line
					(at 35.56 -16.51 180)
					(length 2.54)
					(hide yes)
					(name "NC"
						(effects
							(font
								(size 1.27 1.27)
							)
						)
					)
					(number "6"
						(effects
							(font
								(size 1.27 1.27)
							)
						)
					)
				)
				(pin no_connect line
					(at 35.56 -17.78 180)
					(length 2.54)
					(hide yes)
					(name "NC"
						(effects
							(font
								(size 1.27 1.27)
							)
						)
					)
					(number "8"
						(effects
							(font
								(size 1.27 1.27)
							)
						)
					)
				)
				(pin no_connect line
					(at 35.56 -19.05 180)
					(length 2.54)
					(hide yes)
					(name "NC"
						(effects
							(font
								(size 1.27 1.27)
							)
						)
					)
					(number "20"
						(effects
							(font
								(size 1.27 1.27)
							)
						)
					)
				)
				(pin no_connect line
					(at 35.56 -20.32 180)
					(length 2.54)
					(hide yes)
					(name "NC"
						(effects
							(font
								(size 1.27 1.27)
							)
						)
					)
					(number "22"
						(effects
							(font
								(size 1.27 1.27)
							)
						)
					)
				)
				(pin no_connect line
					(at 35.56 -21.59 180)
					(length 2.54)
					(hide yes)
					(name "NC"
						(effects
							(font
								(size 1.27 1.27)
							)
						)
					)
					(number "24"
						(effects
							(font
								(size 1.27 1.27)
							)
						)
					)
				)
				(pin no_connect line
					(at 35.56 -22.86 180)
					(length 2.54)
					(hide yes)
					(name "NC"
						(effects
							(font
								(size 1.27 1.27)
							)
						)
					)
					(number "26"
						(effects
							(font
								(size 1.27 1.27)
							)
						)
					)
				)
				(pin no_connect line
					(at 35.56 -24.13 180)
					(length 2.54)
					(hide yes)
					(name "NC"
						(effects
							(font
								(size 1.27 1.27)
							)
						)
					)
					(number "28"
						(effects
							(font
								(size 1.27 1.27)
							)
						)
					)
				)
				(pin no_connect line
					(at 35.56 -25.4 180)
					(length 2.54)
					(hide yes)
					(name "NC"
						(effects
							(font
								(size 1.27 1.27)
							)
						)
					)
					(number "30"
						(effects
							(font
								(size 1.27 1.27)
							)
						)
					)
				)
				(pin no_connect line
					(at 35.56 -26.67 180)
					(length 2.54)
					(hide yes)
					(name "NC"
						(effects
							(font
								(size 1.27 1.27)
							)
						)
					)
					(number "32"
						(effects
							(font
								(size 1.27 1.27)
							)
						)
					)
				)
				(pin no_connect line
					(at 35.56 -27.94 180)
					(length 2.54)
					(hide yes)
					(name "NC"
						(effects
							(font
								(size 1.27 1.27)
							)
						)
					)
					(number "34"
						(effects
							(font
								(size 1.27 1.27)
							)
						)
					)
				)
				(pin no_connect line
					(at 35.56 -29.21 180)
					(length 2.54)
					(hide yes)
					(name "NC"
						(effects
							(font
								(size 1.27 1.27)
							)
						)
					)
					(number "36"
						(effects
							(font
								(size 1.27 1.27)
							)
						)
					)
				)
				(pin no_connect line
					(at 35.56 -30.48 180)
					(length 2.54)
					(hide yes)
					(name "NC"
						(effects
							(font
								(size 1.27 1.27)
							)
						)
					)
					(number "40"
						(effects
							(font
								(size 1.27 1.27)
							)
						)
					)
				)
				(pin no_connect line
					(at 35.56 -31.75 180)
					(length 2.54)
					(hide yes)
					(name "NC"
						(effects
							(font
								(size 1.27 1.27)
							)
						)
					)
					(number "42"
						(effects
							(font
								(size 1.27 1.27)
							)
						)
					)
				)
				(pin no_connect line
					(at 35.56 -33.02 180)
					(length 2.54)
					(hide yes)
					(name "NC"
						(effects
							(font
								(size 1.27 1.27)
							)
						)
					)
					(number "44"
						(effects
							(font
								(size 1.27 1.27)
							)
						)
					)
				)
				(pin no_connect line
					(at 35.56 -34.29 180)
					(length 2.54)
					(hide yes)
					(name "NC"
						(effects
							(font
								(size 1.27 1.27)
							)
						)
					)
					(number "46"
						(effects
							(font
								(size 1.27 1.27)
							)
						)
					)
				)
				(pin no_connect line
					(at 35.56 -35.56 180)
					(length 2.54)
					(hide yes)
					(name "NC"
						(effects
							(font
								(size 1.27 1.27)
							)
						)
					)
					(number "48"
						(effects
							(font
								(size 1.27 1.27)
							)
						)
					)
				)
				(pin no_connect line
					(at 35.56 -36.83 180)
					(length 2.54)
					(hide yes)
					(name "NC"
						(effects
							(font
								(size 1.27 1.27)
							)
						)
					)
					(number "56"
						(effects
							(font
								(size 1.27 1.27)
							)
						)
					)
				)
				(pin no_connect line
					(at 35.56 -38.1 180)
					(length 2.54)
					(hide yes)
					(name "NC"
						(effects
							(font
								(size 1.27 1.27)
							)
						)
					)
					(number "58"
						(effects
							(font
								(size 1.27 1.27)
							)
						)
					)
				)
				(pin passive line
					(at 38.1 0 180)
					(length 2.54)
					(name "DAS"
						(effects
							(font
								(size 1.27 1.27)
							)
						)
					)
					(number "10"
						(effects
							(font
								(size 1.27 1.27)
							)
						)
					)
					(alternate "DSS#" passive line)
				)
				(pin passive line
					(at 38.1 -2.54 180)
					(length 2.54)
					(name "DEVSLP"
						(effects
							(font
								(size 1.27 1.27)
							)
						)
					)
					(number "38"
						(effects
							(font
								(size 1.27 1.27)
							)
						)
					)
				)
				(pin passive line
					(at 38.1 -5.08 180)
					(length 2.54)
					(name "PERST#"
						(effects
							(font
								(size 1.27 1.27)
							)
						)
					)
					(number "50"
						(effects
							(font
								(size 1.27 1.27)
							)
						)
					)
				)
				(pin passive line
					(at 38.1 -7.62 180)
					(length 2.54)
					(name "CLKREQ#"
						(effects
							(font
								(size 1.27 1.27)
							)
						)
					)
					(number "52"
						(effects
							(font
								(size 1.27 1.27)
							)
						)
					)
				)
				(pin passive line
					(at 38.1 -10.16 180)
					(length 2.54)
					(name "PEWAKE#"
						(effects
							(font
								(size 1.27 1.27)
							)
						)
					)
					(number "54"
						(effects
							(font
								(size 1.27 1.27)
							)
						)
					)
				)
				(pin passive line
					(at 38.1 -12.7 180)
					(length 2.54)
					(name "SUSCLK"
						(effects
							(font
								(size 1.27 1.27)
							)
						)
					)
					(number "68"
						(effects
							(font
								(size 1.27 1.27)
							)
						)
					)
				)
				(pin passive line
					(at 38.1 -60.96 180)
					(length 2.54)
					(name "GND"
						(effects
							(font
								(size 1.27 1.27)
							)
						)
					)
					(number "1"
						(effects
							(font
								(size 1.27 1.27)
							)
						)
					)
				)
				(pin passive line
					(at 38.1 -60.96 180)
					(length 2.54)
					(hide yes)
					(name "GND"
						(effects
							(font
								(size 1.27 1.27)
							)
						)
					)
					(number "15"
						(effects
							(font
								(size 1.27 1.27)
							)
						)
					)
				)
				(pin passive line
					(at 38.1 -60.96 180)
					(length 2.54)
					(hide yes)
					(name "GND"
						(effects
							(font
								(size 1.27 1.27)
							)
						)
					)
					(number "21"
						(effects
							(font
								(size 1.27 1.27)
							)
						)
					)
				)
				(pin passive line
					(at 38.1 -60.96 180)
					(length 2.54)
					(hide yes)
					(name "GND"
						(effects
							(font
								(size 1.27 1.27)
							)
						)
					)
					(number "27"
						(effects
							(font
								(size 1.27 1.27)
							)
						)
					)
				)
				(pin passive line
					(at 38.1 -60.96 180)
					(length 2.54)
					(hide yes)
					(name "GND"
						(effects
							(font
								(size 1.27 1.27)
							)
						)
					)
					(number "3"
						(effects
							(font
								(size 1.27 1.27)
							)
						)
					)
				)
				(pin passive line
					(at 38.1 -60.96 180)
					(length 2.54)
					(hide yes)
					(name "GND"
						(effects
							(font
								(size 1.27 1.27)
							)
						)
					)
					(number "33"
						(effects
							(font
								(size 1.27 1.27)
							)
						)
					)
				)
				(pin passive line
					(at 38.1 -60.96 180)
					(length 2.54)
					(hide yes)
					(name "GND"
						(effects
							(font
								(size 1.27 1.27)
							)
						)
					)
					(number "39"
						(effects
							(font
								(size 1.27 1.27)
							)
						)
					)
				)
				(pin passive line
					(at 38.1 -60.96 180)
					(length 2.54)
					(hide yes)
					(name "GND"
						(effects
							(font
								(size 1.27 1.27)
							)
						)
					)
					(number "45"
						(effects
							(font
								(size 1.27 1.27)
							)
						)
					)
				)
				(pin passive line
					(at 38.1 -60.96 180)
					(length 2.54)
					(hide yes)
					(name "GND"
						(effects
							(font
								(size 1.27 1.27)
							)
						)
					)
					(number "51"
						(effects
							(font
								(size 1.27 1.27)
							)
						)
					)
				)
				(pin passive line
					(at 38.1 -60.96 180)
					(length 2.54)
					(hide yes)
					(name "GND"
						(effects
							(font
								(size 1.27 1.27)
							)
						)
					)
					(number "57"
						(effects
							(font
								(size 1.27 1.27)
							)
						)
					)
				)
				(pin passive line
					(at 38.1 -60.96 180)
					(length 2.54)
					(hide yes)
					(name "GND"
						(effects
							(font
								(size 1.27 1.27)
							)
						)
					)
					(number "71"
						(effects
							(font
								(size 1.27 1.27)
							)
						)
					)
				)
				(pin passive line
					(at 38.1 -60.96 180)
					(length 2.54)
					(hide yes)
					(name "GND"
						(effects
							(font
								(size 1.27 1.27)
							)
						)
					)
					(number "73"
						(effects
							(font
								(size 1.27 1.27)
							)
						)
					)
				)
				(pin passive line
					(at 38.1 -60.96 180)
					(length 2.54)
					(hide yes)
					(name "GND"
						(effects
							(font
								(size 1.27 1.27)
							)
						)
					)
					(number "75"
						(effects
							(font
								(size 1.27 1.27)
							)
						)
					)
				)
				(pin passive line
					(at 38.1 -60.96 180)
					(length 2.54)
					(hide yes)
					(name "GND"
						(effects
							(font
								(size 1.27 1.27)
							)
						)
					)
					(number "9"
						(effects
							(font
								(size 1.27 1.27)
							)
						)
					)
				)
			)
		)
	(symbol "antmicroMechanicalParts:antmicro_logo"
			(exclude_from_sim no)
			(in_bom no)
			(on_board yes)
			(property "Reference" "N"
				(at 15.24 -5.08 0)
				(effects
					(font
						(size 1.27 1.27)
						(thickness 0.15)
					)
					(justify left bottom)
				)
			)
			(property "Value" "antmicro_logo"
				(at 15.24 -7.62 0)
				(effects
					(font
						(size 1.27 1.27)
						(thickness 0.15)
					)
					(justify left bottom)
				)
			)
			(property "Footprint" "antmicro-footprints:antmicro-logo"
				(at 15.24 -10.16 0)
				(effects
					(font
						(size 1.27 1.27)
						(thickness 0.15)
					)
					(justify left bottom)
					(hide yes)
				)
			)
			(property "Datasheet" ""
				(at 15.24 -12.7 0)
				(effects
					(font
						(size 1.27 1.27)
						(thickness 0.15)
					)
					(justify left bottom)
					(hide yes)
				)
			)
			(property "Description" "Mechanical part"
				(at 15.24 -22.86 0)
				(effects
					(font
						(size 1.27 1.27)
					)
					(justify left bottom)
					(hide yes)
				)
			)
			(property "MPN" ""
				(at 0 0 0)
				(effects
					(font
						(size 1.27 1.27)
					)
				)
			)
			(property "Manufacturer" ""
				(at 15.24 -20.32 0)
				(effects
					(font
						(size 1.27 1.27)
						(thickness 0.15)
					)
					(justify left bottom)
					(hide yes)
				)
			)
			(property "Author" "Antmicro"
				(at 15.24 -15.24 0)
				(effects
					(font
						(size 1.27 1.27)
						(thickness 0.15)
					)
					(justify left bottom)
					(hide yes)
				)
			)
			(property "License" "Apache-2.0"
				(at 15.24 -17.78 0)
				(effects
					(font
						(size 1.27 1.27)
						(thickness 0.15)
					)
					(justify left bottom)
					(hide yes)
				)
			)
			(symbol "antmicro_logo_1_1"
				(text "Logo"
					(at 0 0 0)
					(effects
						(font
							(size 1.27 1.27)
							(thickness 0.15)
						)
						(justify left bottom)
					)
				)
			)
		)
	(symbol "antmicroMechanicalParts:oshw_logo"
			(exclude_from_sim no)
			(in_bom no)
			(on_board yes)
			(property "Reference" "N"
				(at 15.24 -5.08 0)
				(effects
					(font
						(size 1.27 1.27)
						(thickness 0.15)
					)
					(justify left bottom)
				)
			)
			(property "Value" "oshw_logo"
				(at 15.24 -7.62 0)
				(effects
					(font
						(size 1.27 1.27)
						(thickness 0.15)
					)
					(justify left bottom)
				)
			)
			(property "Footprint" "antmicro-footprints:oshw-logo"
				(at 15.24 -10.16 0)
				(effects
					(font
						(size 1.27 1.27)
						(thickness 0.15)
					)
					(justify left bottom)
					(hide yes)
				)
			)
			(property "Datasheet" ""
				(at 15.24 -12.7 0)
				(effects
					(font
						(size 1.27 1.27)
						(thickness 0.15)
					)
					(justify left bottom)
					(hide yes)
				)
			)
			(property "Description" "Mechanical part"
				(at 15.24 -22.86 0)
				(effects
					(font
						(size 1.27 1.27)
					)
					(justify left bottom)
					(hide yes)
				)
			)
			(property "Author" "Antmicro"
				(at 15.24 -15.24 0)
				(effects
					(font
						(size 1.27 1.27)
						(thickness 0.15)
					)
					(justify left bottom)
					(hide yes)
				)
			)
			(property "License" "Apache-2.0"
				(at 15.24 -17.78 0)
				(effects
					(font
						(size 1.27 1.27)
						(thickness 0.15)
					)
					(justify left bottom)
					(hide yes)
				)
			)
			(property "MPN" ""
				(at 0 0 0)
				(effects
					(font
						(size 1.27 1.27)
					)
				)
			)
			(property "Manufacturer" ""
				(at 15.24 -20.32 0)
				(effects
					(font
						(size 1.27 1.27)
						(thickness 0.15)
					)
					(justify left bottom)
					(hide yes)
				)
			)
			(symbol "oshw_logo_1_1"
				(text "Logo"
					(at 0 0 0)
					(effects
						(font
							(size 1.27 1.27)
							(thickness 0.15)
						)
						(justify left bottom)
					)
				)
			)
		)
	(symbol "antmicroPciConnectors:Socket_Samtec_PCIE_PCIe-x4_PCIE-064-02-X-D-EMSX"
			(exclude_from_sim no)
			(in_bom yes)
			(on_board yes)
			(property "Reference" "J"
				(at 48.26 -2.54 0)
				(effects
					(font
						(size 1.27 1.27)
						(thickness 0.15)
					)
					(justify left bottom)
				)
			)
			(property "Value" "Socket_Samtec_PCIE_PCIe-x4_PCIE-064-02-X-D-EMSX"
				(at 48.26 -7.62 0)
				(effects
					(font
						(size 1.27 1.27)
						(thickness 0.15)
					)
					(justify left bottom)
					(hide yes)
				)
			)
			(property "Footprint" "antmicro-footprints:Socket_Samtec_PCIE_PCIe-x4_PCIE-064-02-X-D-EMSX"
				(at 48.26 -10.16 0)
				(effects
					(font
						(size 1.27 1.27)
						(thickness 0.15)
					)
					(justify left bottom)
					(hide yes)
				)
			)
			(property "Datasheet" "http://www.farnell.com/datasheets/2048385.pdf?_ga=2.224413790.550525831.1572511829-156563690.1566371002&_gac=1.194368863.1572511829.Cj0KCQjwjOrtBRCcARIsAEq4rW4MDAz553xUSGW1I2S05saoepO8CZq5otyVO6_gct6IiE-jnZiday4aAmKSEALw_wcB"
				(at 48.26 -12.7 0)
				(effects
					(font
						(size 1.27 1.27)
						(thickness 0.15)
					)
					(justify left bottom)
					(hide yes)
				)
			)
			(property "Description" "PCIe x4 connector"
				(at 48.26 -22.86 0)
				(effects
					(font
						(size 1.27 1.27)
					)
					(justify left bottom)
					(hide yes)
				)
			)
			(property "MPN" "PCIE-064-02-X-D-EMSX"
				(at 48.26 -5.08 0)
				(effects
					(font
						(size 1.27 1.27)
						(thickness 0.15)
					)
					(justify left bottom)
				)
			)
			(property "Manufacturer" "Samtec"
				(at 48.26 -15.24 0)
				(effects
					(font
						(size 1.27 1.27)
						(thickness 0.15)
					)
					(justify left bottom)
					(hide yes)
				)
			)
			(property "Author" "Antmicro"
				(at 48.26 -17.78 0)
				(effects
					(font
						(size 1.27 1.27)
						(thickness 0.15)
					)
					(justify left bottom)
					(hide yes)
				)
			)
			(property "License" "Apache-2.0"
				(at 48.26 -20.32 0)
				(effects
					(font
						(size 1.27 1.27)
						(thickness 0.15)
					)
					(justify left bottom)
					(hide yes)
				)
			)
			(property "ki_keywords" "CONNECTOR"
				(at 0 0 0)
				(effects
					(font
						(size 1.27 1.27)
					)
					(hide yes)
				)
			)
			(symbol "Socket_Samtec_PCIE_PCIe-x4_PCIE-064-02-X-D-EMSX_0_1"
				(rectangle
					(start 3.81 2.54)
					(end 29.21 -83.82)
					(stroke
						(width 0.254)
						(type default)
					)
					(fill
						(type background)
					)
				)
			)
			(symbol "Socket_Samtec_PCIE_PCIe-x4_PCIE-064-02-X-D-EMSX_1_1"
				(pin passive line
					(at 0 0 0)
					(length 3.81)
					(name "+12V"
						(effects
							(font
								(size 1.27 1.27)
							)
						)
					)
					(number "B1"
						(effects
							(font
								(size 1.27 1.27)
							)
						)
					)
				)
				(pin passive line
					(at 0 -2.54 0)
					(length 3.81)
					(name "+12V"
						(effects
							(font
								(size 1.27 1.27)
							)
						)
					)
					(number "B2"
						(effects
							(font
								(size 1.27 1.27)
							)
						)
					)
				)
				(pin passive line
					(at 0 -5.08 0)
					(length 3.81)
					(name "+12V"
						(effects
							(font
								(size 1.27 1.27)
							)
						)
					)
					(number "B3"
						(effects
							(font
								(size 1.27 1.27)
							)
						)
					)
				)
				(pin passive line
					(at 0 -7.62 0)
					(length 3.81)
					(name "GND"
						(effects
							(font
								(size 1.27 1.27)
							)
						)
					)
					(number "B4"
						(effects
							(font
								(size 1.27 1.27)
							)
						)
					)
				)
				(pin passive line
					(at 0 -10.16 0)
					(length 3.81)
					(name "SMCLK"
						(effects
							(font
								(size 1.27 1.27)
							)
						)
					)
					(number "B5"
						(effects
							(font
								(size 1.27 1.27)
							)
						)
					)
				)
				(pin passive line
					(at 0 -12.7 0)
					(length 3.81)
					(name "SMDAT"
						(effects
							(font
								(size 1.27 1.27)
							)
						)
					)
					(number "B6"
						(effects
							(font
								(size 1.27 1.27)
							)
						)
					)
				)
				(pin passive line
					(at 0 -15.24 0)
					(length 3.81)
					(name "GND"
						(effects
							(font
								(size 1.27 1.27)
							)
						)
					)
					(number "B7"
						(effects
							(font
								(size 1.27 1.27)
							)
						)
					)
				)
				(pin passive line
					(at 0 -17.78 0)
					(length 3.81)
					(name "+3V3"
						(effects
							(font
								(size 1.27 1.27)
							)
						)
					)
					(number "B8"
						(effects
							(font
								(size 1.27 1.27)
							)
						)
					)
				)
				(pin passive line
					(at 0 -20.32 0)
					(length 3.81)
					(name "JTAG1"
						(effects
							(font
								(size 1.27 1.27)
							)
						)
					)
					(number "B9"
						(effects
							(font
								(size 1.27 1.27)
							)
						)
					)
				)
				(pin passive line
					(at 0 -22.86 0)
					(length 3.81)
					(name "+3V3aux"
						(effects
							(font
								(size 1.27 1.27)
							)
						)
					)
					(number "B10"
						(effects
							(font
								(size 1.27 1.27)
							)
						)
					)
				)
				(pin passive line
					(at 0 -25.4 0)
					(length 3.81)
					(name "WAKE#"
						(effects
							(font
								(size 1.27 1.27)
							)
						)
					)
					(number "B11"
						(effects
							(font
								(size 1.27 1.27)
							)
						)
					)
				)
				(pin passive line
					(at 0 -30.48 0)
					(length 3.81)
					(name "RSVD"
						(effects
							(font
								(size 1.27 1.27)
							)
						)
					)
					(number "B12"
						(effects
							(font
								(size 1.27 1.27)
							)
						)
					)
				)
				(pin passive line
					(at 0 -33.02 0)
					(length 3.81)
					(name "GND"
						(effects
							(font
								(size 1.27 1.27)
							)
						)
					)
					(number "B13"
						(effects
							(font
								(size 1.27 1.27)
							)
						)
					)
				)
				(pin passive line
					(at 0 -35.56 0)
					(length 3.81)
					(name "HSOp(0)"
						(effects
							(font
								(size 1.27 1.27)
							)
						)
					)
					(number "B14"
						(effects
							(font
								(size 1.27 1.27)
							)
						)
					)
				)
				(pin passive line
					(at 0 -38.1 0)
					(length 3.81)
					(name "HSOn(0)"
						(effects
							(font
								(size 1.27 1.27)
							)
						)
					)
					(number "B15"
						(effects
							(font
								(size 1.27 1.27)
							)
						)
					)
				)
				(pin passive line
					(at 0 -40.64 0)
					(length 3.81)
					(name "GND"
						(effects
							(font
								(size 1.27 1.27)
							)
						)
					)
					(number "B16"
						(effects
							(font
								(size 1.27 1.27)
							)
						)
					)
				)
				(pin passive line
					(at 0 -43.18 0)
					(length 3.81)
					(name "PRSNT#2"
						(effects
							(font
								(size 1.27 1.27)
							)
						)
					)
					(number "B17"
						(effects
							(font
								(size 1.27 1.27)
							)
						)
					)
				)
				(pin passive line
					(at 0 -45.72 0)
					(length 3.81)
					(name "GND"
						(effects
							(font
								(size 1.27 1.27)
							)
						)
					)
					(number "B18"
						(effects
							(font
								(size 1.27 1.27)
							)
						)
					)
				)
				(pin passive line
					(at 0 -48.26 0)
					(length 3.81)
					(name "HSOp(1)"
						(effects
							(font
								(size 1.27 1.27)
							)
						)
					)
					(number "B19"
						(effects
							(font
								(size 1.27 1.27)
							)
						)
					)
				)
				(pin passive line
					(at 0 -50.8 0)
					(length 3.81)
					(name "HSOn(1)"
						(effects
							(font
								(size 1.27 1.27)
							)
						)
					)
					(number "B20"
						(effects
							(font
								(size 1.27 1.27)
							)
						)
					)
				)
				(pin passive line
					(at 0 -53.34 0)
					(length 3.81)
					(name "GND"
						(effects
							(font
								(size 1.27 1.27)
							)
						)
					)
					(number "B21"
						(effects
							(font
								(size 1.27 1.27)
							)
						)
					)
				)
				(pin passive line
					(at 0 -55.88 0)
					(length 3.81)
					(name "GND"
						(effects
							(font
								(size 1.27 1.27)
							)
						)
					)
					(number "B22"
						(effects
							(font
								(size 1.27 1.27)
							)
						)
					)
				)
				(pin passive line
					(at 0 -58.42 0)
					(length 3.81)
					(name "HSOp(2)"
						(effects
							(font
								(size 1.27 1.27)
							)
						)
					)
					(number "B23"
						(effects
							(font
								(size 1.27 1.27)
							)
						)
					)
				)
				(pin passive line
					(at 0 -60.96 0)
					(length 3.81)
					(name "HSOn(2)"
						(effects
							(font
								(size 1.27 1.27)
							)
						)
					)
					(number "B24"
						(effects
							(font
								(size 1.27 1.27)
							)
						)
					)
				)
				(pin passive line
					(at 0 -63.5 0)
					(length 3.81)
					(name "GND"
						(effects
							(font
								(size 1.27 1.27)
							)
						)
					)
					(number "B25"
						(effects
							(font
								(size 1.27 1.27)
							)
						)
					)
				)
				(pin passive line
					(at 0 -66.04 0)
					(length 3.81)
					(name "GND"
						(effects
							(font
								(size 1.27 1.27)
							)
						)
					)
					(number "B26"
						(effects
							(font
								(size 1.27 1.27)
							)
						)
					)
				)
				(pin passive line
					(at 0 -68.58 0)
					(length 3.81)
					(name "HSOp(3)"
						(effects
							(font
								(size 1.27 1.27)
							)
						)
					)
					(number "B27"
						(effects
							(font
								(size 1.27 1.27)
							)
						)
					)
				)
				(pin passive line
					(at 0 -71.12 0)
					(length 3.81)
					(name "HSOn(3)"
						(effects
							(font
								(size 1.27 1.27)
							)
						)
					)
					(number "B28"
						(effects
							(font
								(size 1.27 1.27)
							)
						)
					)
				)
				(pin passive line
					(at 0 -73.66 0)
					(length 3.81)
					(name "GND"
						(effects
							(font
								(size 1.27 1.27)
							)
						)
					)
					(number "B29"
						(effects
							(font
								(size 1.27 1.27)
							)
						)
					)
				)
				(pin passive line
					(at 0 -76.2 0)
					(length 3.81)
					(name "RSVD"
						(effects
							(font
								(size 1.27 1.27)
							)
						)
					)
					(number "B30"
						(effects
							(font
								(size 1.27 1.27)
							)
						)
					)
				)
				(pin passive line
					(at 0 -78.74 0)
					(length 3.81)
					(name "PRSNT#2"
						(effects
							(font
								(size 1.27 1.27)
							)
						)
					)
					(number "B31"
						(effects
							(font
								(size 1.27 1.27)
							)
						)
					)
				)
				(pin passive line
					(at 0 -81.28 0)
					(length 3.81)
					(name "GND"
						(effects
							(font
								(size 1.27 1.27)
							)
						)
					)
					(number "B32"
						(effects
							(font
								(size 1.27 1.27)
							)
						)
					)
				)
				(pin passive line
					(at 33.02 0 180)
					(length 3.81)
					(name "PRSNT#1"
						(effects
							(font
								(size 1.27 1.27)
							)
						)
					)
					(number "A1"
						(effects
							(font
								(size 1.27 1.27)
							)
						)
					)
				)
				(pin passive line
					(at 33.02 -2.54 180)
					(length 3.81)
					(name "+12V"
						(effects
							(font
								(size 1.27 1.27)
							)
						)
					)
					(number "A2"
						(effects
							(font
								(size 1.27 1.27)
							)
						)
					)
				)
				(pin passive line
					(at 33.02 -5.08 180)
					(length 3.81)
					(name "+12V"
						(effects
							(font
								(size 1.27 1.27)
							)
						)
					)
					(number "A3"
						(effects
							(font
								(size 1.27 1.27)
							)
						)
					)
				)
				(pin passive line
					(at 33.02 -7.62 180)
					(length 3.81)
					(name "GND"
						(effects
							(font
								(size 1.27 1.27)
							)
						)
					)
					(number "A4"
						(effects
							(font
								(size 1.27 1.27)
							)
						)
					)
				)
				(pin passive line
					(at 33.02 -10.16 180)
					(length 3.81)
					(name "JTAG2"
						(effects
							(font
								(size 1.27 1.27)
							)
						)
					)
					(number "A5"
						(effects
							(font
								(size 1.27 1.27)
							)
						)
					)
				)
				(pin passive line
					(at 33.02 -12.7 180)
					(length 3.81)
					(name "JTAG3"
						(effects
							(font
								(size 1.27 1.27)
							)
						)
					)
					(number "A6"
						(effects
							(font
								(size 1.27 1.27)
							)
						)
					)
				)
				(pin passive line
					(at 33.02 -15.24 180)
					(length 3.81)
					(name "JTAG4"
						(effects
							(font
								(size 1.27 1.27)
							)
						)
					)
					(number "A7"
						(effects
							(font
								(size 1.27 1.27)
							)
						)
					)
				)
				(pin passive line
					(at 33.02 -17.78 180)
					(length 3.81)
					(name "JTAG5"
						(effects
							(font
								(size 1.27 1.27)
							)
						)
					)
					(number "A8"
						(effects
							(font
								(size 1.27 1.27)
							)
						)
					)
				)
				(pin passive line
					(at 33.02 -20.32 180)
					(length 3.81)
					(name "+3V3"
						(effects
							(font
								(size 1.27 1.27)
							)
						)
					)
					(number "A9"
						(effects
							(font
								(size 1.27 1.27)
							)
						)
					)
				)
				(pin passive line
					(at 33.02 -22.86 180)
					(length 3.81)
					(name "+3V3"
						(effects
							(font
								(size 1.27 1.27)
							)
						)
					)
					(number "A10"
						(effects
							(font
								(size 1.27 1.27)
							)
						)
					)
				)
				(pin passive line
					(at 33.02 -25.4 180)
					(length 3.81)
					(name "PWRGD"
						(effects
							(font
								(size 1.27 1.27)
							)
						)
					)
					(number "A11"
						(effects
							(font
								(size 1.27 1.27)
							)
						)
					)
				)
				(pin passive line
					(at 33.02 -30.48 180)
					(length 3.81)
					(name "GND"
						(effects
							(font
								(size 1.27 1.27)
							)
						)
					)
					(number "A12"
						(effects
							(font
								(size 1.27 1.27)
							)
						)
					)
				)
				(pin passive line
					(at 33.02 -33.02 180)
					(length 3.81)
					(name "REFCLK+"
						(effects
							(font
								(size 1.27 1.27)
							)
						)
					)
					(number "A13"
						(effects
							(font
								(size 1.27 1.27)
							)
						)
					)
				)
				(pin passive line
					(at 33.02 -35.56 180)
					(length 3.81)
					(name "REFCLK-"
						(effects
							(font
								(size 1.27 1.27)
							)
						)
					)
					(number "A14"
						(effects
							(font
								(size 1.27 1.27)
							)
						)
					)
				)
				(pin passive line
					(at 33.02 -38.1 180)
					(length 3.81)
					(name "GND"
						(effects
							(font
								(size 1.27 1.27)
							)
						)
					)
					(number "A15"
						(effects
							(font
								(size 1.27 1.27)
							)
						)
					)
				)
				(pin passive line
					(at 33.02 -40.64 180)
					(length 3.81)
					(name "HSIp(0)"
						(effects
							(font
								(size 1.27 1.27)
							)
						)
					)
					(number "A16"
						(effects
							(font
								(size 1.27 1.27)
							)
						)
					)
				)
				(pin passive line
					(at 33.02 -43.18 180)
					(length 3.81)
					(name "HSIn(0)"
						(effects
							(font
								(size 1.27 1.27)
							)
						)
					)
					(number "A17"
						(effects
							(font
								(size 1.27 1.27)
							)
						)
					)
				)
				(pin passive line
					(at 33.02 -45.72 180)
					(length 3.81)
					(name "GND"
						(effects
							(font
								(size 1.27 1.27)
							)
						)
					)
					(number "A18"
						(effects
							(font
								(size 1.27 1.27)
							)
						)
					)
				)
				(pin passive line
					(at 33.02 -48.26 180)
					(length 3.81)
					(name "RSVD"
						(effects
							(font
								(size 1.27 1.27)
							)
						)
					)
					(number "A19"
						(effects
							(font
								(size 1.27 1.27)
							)
						)
					)
				)
				(pin passive line
					(at 33.02 -50.8 180)
					(length 3.81)
					(name "GND"
						(effects
							(font
								(size 1.27 1.27)
							)
						)
					)
					(number "A20"
						(effects
							(font
								(size 1.27 1.27)
							)
						)
					)
				)
				(pin passive line
					(at 33.02 -53.34 180)
					(length 3.81)
					(name "HSIp(1)"
						(effects
							(font
								(size 1.27 1.27)
							)
						)
					)
					(number "A21"
						(effects
							(font
								(size 1.27 1.27)
							)
						)
					)
				)
				(pin passive line
					(at 33.02 -55.88 180)
					(length 3.81)
					(name "HSIn(1)"
						(effects
							(font
								(size 1.27 1.27)
							)
						)
					)
					(number "A22"
						(effects
							(font
								(size 1.27 1.27)
							)
						)
					)
				)
				(pin passive line
					(at 33.02 -58.42 180)
					(length 3.81)
					(name "GND"
						(effects
							(font
								(size 1.27 1.27)
							)
						)
					)
					(number "A23"
						(effects
							(font
								(size 1.27 1.27)
							)
						)
					)
				)
				(pin passive line
					(at 33.02 -60.96 180)
					(length 3.81)
					(name "GND"
						(effects
							(font
								(size 1.27 1.27)
							)
						)
					)
					(number "A24"
						(effects
							(font
								(size 1.27 1.27)
							)
						)
					)
				)
				(pin passive line
					(at 33.02 -63.5 180)
					(length 3.81)
					(name "HSIp(2)"
						(effects
							(font
								(size 1.27 1.27)
							)
						)
					)
					(number "A25"
						(effects
							(font
								(size 1.27 1.27)
							)
						)
					)
				)
				(pin passive line
					(at 33.02 -66.04 180)
					(length 3.81)
					(name "HSIn(2)"
						(effects
							(font
								(size 1.27 1.27)
							)
						)
					)
					(number "A26"
						(effects
							(font
								(size 1.27 1.27)
							)
						)
					)
				)
				(pin passive line
					(at 33.02 -68.58 180)
					(length 3.81)
					(name "GND"
						(effects
							(font
								(size 1.27 1.27)
							)
						)
					)
					(number "A27"
						(effects
							(font
								(size 1.27 1.27)
							)
						)
					)
				)
				(pin input line
					(at 33.02 -71.12 180)
					(length 3.81)
					(name "GND"
						(effects
							(font
								(size 1.27 1.27)
							)
						)
					)
					(number "A28"
						(effects
							(font
								(size 1.27 1.27)
							)
						)
					)
				)
				(pin passive line
					(at 33.02 -73.66 180)
					(length 3.81)
					(name "HSIp(3)"
						(effects
							(font
								(size 1.27 1.27)
							)
						)
					)
					(number "A29"
						(effects
							(font
								(size 1.27 1.27)
							)
						)
					)
				)
				(pin passive line
					(at 33.02 -76.2 180)
					(length 3.81)
					(name "HSIn(3)"
						(effects
							(font
								(size 1.27 1.27)
							)
						)
					)
					(number "A30"
						(effects
							(font
								(size 1.27 1.27)
							)
						)
					)
				)
				(pin passive line
					(at 33.02 -78.74 180)
					(length 3.81)
					(name "GND"
						(effects
							(font
								(size 1.27 1.27)
							)
						)
					)
					(number "A31"
						(effects
							(font
								(size 1.27 1.27)
							)
						)
					)
				)
				(pin passive line
					(at 33.02 -81.28 180)
					(length 3.81)
					(name "RSVD"
						(effects
							(font
								(size 1.27 1.27)
							)
						)
					)
					(number "A32"
						(effects
							(font
								(size 1.27 1.27)
							)
						)
					)
				)
			)
		)
	(symbol "antmicroPogoPins:Harwin_1x1_H3.5mm_Pad2.2mm_P70-1000045R"
			(exclude_from_sim no)
			(in_bom yes)
			(on_board yes)
			(property "Reference" "J"
				(at 27.94 -2.54 0)
				(effects
					(font
						(size 1.27 1.27)
						(thickness 0.15)
					)
					(justify left bottom)
				)
			)
			(property "Value" "Harwin_1x1_H3.5mm_Pad2.2mm_P70-1000045R"
				(at 27.94 -7.62 0)
				(effects
					(font
						(size 1.27 1.27)
						(thickness 0.15)
					)
					(justify left bottom)
					(hide yes)
				)
			)
			(property "Footprint" "antmicro-footprints:Harwin_1x1_H3.5mm_Pad2.2mm_P70-1000045R"
				(at 27.94 -10.16 0)
				(effects
					(font
						(size 1.27 1.27)
						(thickness 0.15)
					)
					(justify left bottom)
					(hide yes)
				)
			)
			(property "Datasheet" "https://eu.mouser.com/datasheet/2/181/P70_10X-1018735.pdf"
				(at 27.94 -12.7 0)
				(effects
					(font
						(size 1.27 1.27)
						(thickness 0.15)
					)
					(justify left bottom)
					(hide yes)
				)
			)
			(property "Description" "Contact Spring Surface Mount"
				(at 27.94 -22.86 0)
				(effects
					(font
						(size 1.27 1.27)
					)
					(justify left bottom)
					(hide yes)
				)
			)
			(property "MPN" "P70-1000045R"
				(at 27.94 -5.08 0)
				(effects
					(font
						(size 1.27 1.27)
						(thickness 0.15)
					)
					(justify left bottom)
				)
			)
			(property "Manufacturer" "Harwin"
				(at 27.94 -15.24 0)
				(effects
					(font
						(size 1.27 1.27)
						(thickness 0.15)
					)
					(justify left bottom)
					(hide yes)
				)
			)
			(property "Author" "Antmicro"
				(at 27.94 -17.78 0)
				(effects
					(font
						(size 1.27 1.27)
						(thickness 0.15)
					)
					(justify left bottom)
					(hide yes)
				)
			)
			(property "License" "Apache-2.0"
				(at 27.94 -20.32 0)
				(effects
					(font
						(size 1.27 1.27)
						(thickness 0.15)
					)
					(justify left bottom)
					(hide yes)
				)
			)
			(property "ki_keywords" "POGO-PIN, CONNECTOR, SMT"
				(at 0 0 0)
				(effects
					(font
						(size 1.27 1.27)
					)
					(hide yes)
				)
			)
			(symbol "Harwin_1x1_H3.5mm_Pad2.2mm_P70-1000045R_0_1"
				(arc
					(start 12.7 2.54)
					(mid 14.4961 1.7961)
					(end 15.24 0)
					(stroke
						(width 0)
						(type default)
					)
					(fill
						(type background)
					)
				)
				(arc
					(start 15.24 0)
					(mid 14.4961 -1.7961)
					(end 12.7 -2.54)
					(stroke
						(width 0)
						(type default)
					)
					(fill
						(type background)
					)
				)
				(polyline
					(pts
						(xy 12.7 -2.54) (xy 2.54 -2.54) (xy 2.54 2.54) (xy 12.7 2.54)
					)
					(stroke
						(width 0)
						(type default)
					)
					(fill
						(type background)
					)
				)
			)
			(symbol "Harwin_1x1_H3.5mm_Pad2.2mm_P70-1000045R_1_1"
				(pin passive line
					(at 0 0 0)
					(length 2.54)
					(name "~"
						(effects
							(font
								(size 1.27 1.27)
							)
						)
					)
					(number "1"
						(effects
							(font
								(size 1.27 1.27)
							)
						)
					)
				)
			)
		)
	(symbol "antmicroResistors0402:R_0R_0402"
			(pin_numbers
				(hide yes)
			)
			(pin_names
				(hide yes)
			)
			(exclude_from_sim no)
			(in_bom yes)
			(on_board yes)
			(property "Reference" "R"
				(at 20.32 -5.08 0)
				(effects
					(font
						(size 1.27 1.27)
						(thickness 0.15)
					)
					(justify left bottom)
				)
			)
			(property "Value" "R_0R_0402"
				(at 20.32 -12.7 0)
				(effects
					(font
						(size 1.27 1.27)
						(thickness 0.15)
					)
					(justify left bottom)
					(hide yes)
				)
			)
			(property "Footprint" "antmicro-footprints:R_0402_1005Metric"
				(at 20.32 -15.24 0)
				(effects
					(font
						(size 1.27 1.27)
						(thickness 0.15)
					)
					(justify left bottom)
					(hide yes)
				)
			)
			(property "Datasheet" "https://industrial.panasonic.com/cdbs/www-data/pdf/RDA0000/AOA0000C301.pdf"
				(at 20.32 -17.78 0)
				(effects
					(font
						(size 1.27 1.27)
						(thickness 0.15)
					)
					(justify left bottom)
					(hide yes)
				)
			)
			(property "Description" "SMD Chip Resistor, Jumper, 0 ohm, 100 mW, 0402 [1005 Metric], Thick Film, General Purpose"
				(at 20.32 -33.02 0)
				(effects
					(font
						(size 1.27 1.27)
					)
					(justify left bottom)
					(hide yes)
				)
			)
			(property "MPN" "ERJ2GE0R00X"
				(at 20.32 -20.32 0)
				(effects
					(font
						(size 1.27 1.27)
						(thickness 0.15)
					)
					(justify left bottom)
					(hide yes)
				)
			)
			(property "Manufacturer" "Panasonic"
				(at 20.32 -22.86 0)
				(effects
					(font
						(size 1.27 1.27)
						(thickness 0.15)
					)
					(justify left bottom)
					(hide yes)
				)
			)
			(property "License" "Apache-2.0"
				(at 20.32 -25.4 0)
				(effects
					(font
						(size 1.27 1.27)
						(thickness 0.15)
					)
					(justify left bottom)
					(hide yes)
				)
			)
			(property "Author" "Antmicro"
				(at 20.32 -27.94 0)
				(effects
					(font
						(size 1.27 1.27)
						(thickness 0.15)
					)
					(justify left bottom)
					(hide yes)
				)
			)
			(property "Val" "0R"
				(at 20.32 -7.62 0)
				(effects
					(font
						(size 1.27 1.27)
						(thickness 0.15)
					)
					(justify left bottom)
				)
			)
			(property "Tolerance" "~"
				(at 20.32 -10.16 0)
				(effects
					(font
						(size 1.27 1.27)
					)
					(justify left bottom)
					(hide yes)
				)
			)
			(property "Current" "1A"
				(at 20.32 -30.48 0)
				(effects
					(font
						(size 1.27 1.27)
						(thickness 0.15)
					)
					(justify left bottom)
					(hide yes)
				)
			)
			(property "ki_keywords" "0402, SMT, RESISTOR, PASSIVE"
				(at 0 0 0)
				(effects
					(font
						(size 1.27 1.27)
					)
					(hide yes)
				)
			)
			(symbol "R_0R_0402_0_1"
				(rectangle
					(start 0.635 0.889)
					(end 4.445 -0.889)
					(stroke
						(width 0.254)
						(type default)
					)
					(fill
						(type none)
					)
				)
			)
			(symbol "R_0R_0402_1_1"
				(pin passive line
					(at 0 0 0)
					(length 0.635)
					(name "~"
						(effects
							(font
								(size 1.27 1.27)
							)
						)
					)
					(number "1"
						(effects
							(font
								(size 1.27 1.27)
							)
						)
					)
				)
				(pin passive line
					(at 5.08 0 180)
					(length 0.635)
					(name "~"
						(effects
							(font
								(size 1.27 1.27)
							)
						)
					)
					(number "2"
						(effects
							(font
								(size 1.27 1.27)
							)
						)
					)
				)
			)
		)
	(symbol "antmicroWire2BoardConnectors:Molex_KK_1x4_22-05-3041_Horizontal"
			(exclude_from_sim no)
			(in_bom yes)
			(on_board yes)
			(property "Reference" "J"
				(at 20.32 -5.08 0)
				(effects
					(font
						(size 1.27 1.27)
						(thickness 0.15)
					)
					(justify left bottom)
				)
			)
			(property "Value" "Molex_KK_1x4_22-05-3041_Horizontal"
				(at 20.32 -10.16 0)
				(effects
					(font
						(size 1.27 1.27)
						(thickness 0.15)
					)
					(justify left bottom)
					(hide yes)
				)
			)
			(property "Footprint" "antmicro-footprints:Conn_Molex_KK_1x4_22-05-3041_Horizontal"
				(at 20.32 -12.7 0)
				(effects
					(font
						(size 1.27 1.27)
						(thickness 0.15)
					)
					(justify left bottom)
					(hide yes)
				)
			)
			(property "Datasheet" "https://www.molex.com/content/dam/molex/molex-dot-com/products/automated/en-us/salesdrawingpdf/747/7478/022053041_sd.pdf?inline"
				(at 20.32 -15.24 0)
				(effects
					(font
						(size 1.27 1.27)
						(thickness 0.15)
					)
					(justify left bottom)
					(hide yes)
				)
			)
			(property "Description" "Connector Header, THT,  4x1"
				(at 20.32 -25.4 0)
				(effects
					(font
						(size 1.27 1.27)
					)
					(justify left bottom)
					(hide yes)
				)
			)
			(property "MPN" "22-05-3041"
				(at 20.32 -7.62 0)
				(effects
					(font
						(size 1.27 1.27)
						(thickness 0.15)
					)
					(justify left bottom)
				)
			)
			(property "Manufacturer" "Molex"
				(at 20.32 -17.78 0)
				(effects
					(font
						(size 1.27 1.27)
						(thickness 0.15)
					)
					(justify left bottom)
					(hide yes)
				)
			)
			(property "Author" "Antmicro"
				(at 20.32 -20.32 0)
				(effects
					(font
						(size 1.27 1.27)
						(thickness 0.15)
					)
					(justify left bottom)
					(hide yes)
				)
			)
			(property "License" "Apache-2.0"
				(at 20.32 -22.86 0)
				(effects
					(font
						(size 1.27 1.27)
						(thickness 0.15)
					)
					(justify left bottom)
					(hide yes)
				)
			)
			(property "ki_keywords" "CONNECTOR, HEADER, WIRE-BOARD, THT"
				(at 0 0 0)
				(effects
					(font
						(size 1.27 1.27)
					)
					(hide yes)
				)
			)
			(symbol "Molex_KK_1x4_22-05-3041_Horizontal_1_1"
				(rectangle
					(start 4.191 -0.254)
					(end 3.683 0.254)
					(stroke
						(width 0.254)
						(type solid)
					)
					(fill
						(type background)
					)
				)
				(rectangle
					(start 4.191 -2.794)
					(end 3.683 -2.286)
					(stroke
						(width 0.254)
						(type solid)
					)
					(fill
						(type background)
					)
				)
				(rectangle
					(start 4.191 -5.334)
					(end 3.683 -4.826)
					(stroke
						(width 0.254)
						(type solid)
					)
					(fill
						(type background)
					)
				)
				(rectangle
					(start 4.191 -7.874)
					(end 3.683 -7.366)
					(stroke
						(width 0.254)
						(type solid)
					)
					(fill
						(type background)
					)
				)
				(rectangle
					(start 5.08 -8.89)
					(end 2.54 1.27)
					(stroke
						(width 0.254)
						(type solid)
					)
					(fill
						(type background)
					)
				)
				(pin passive line
					(at 0 0 0)
					(length 2.54)
					(name "~"
						(effects
							(font
								(size 1.27 1.27)
							)
						)
					)
					(number "1"
						(effects
							(font
								(size 1.27 1.27)
							)
						)
					)
				)
				(pin passive line
					(at 0 -2.54 0)
					(length 2.54)
					(name "~"
						(effects
							(font
								(size 1.27 1.27)
							)
						)
					)
					(number "2"
						(effects
							(font
								(size 1.27 1.27)
							)
						)
					)
				)
				(pin passive line
					(at 0 -5.08 0)
					(length 2.54)
					(name "~"
						(effects
							(font
								(size 1.27 1.27)
							)
						)
					)
					(number "3"
						(effects
							(font
								(size 1.27 1.27)
							)
						)
					)
				)
				(pin passive line
					(at 0 -7.62 0)
					(length 2.54)
					(name "~"
						(effects
							(font
								(size 1.27 1.27)
							)
						)
					)
					(number "4"
						(effects
							(font
								(size 1.27 1.27)
							)
						)
					)
				)
			)
		)
	(symbol "antmicropower:+12V"
			(power)
			(pin_names
				(offset 0)
			)
			(exclude_from_sim no)
			(in_bom yes)
			(on_board yes)
			(property "Reference" "#PWR"
				(at 0 -3.81 0)
				(effects
					(font
						(size 1.27 1.27)
					)
					(hide yes)
				)
			)
			(property "Value" "+12V"
				(at 0 3.556 0)
				(effects
					(font
						(size 1.27 1.27)
					)
				)
			)
			(property "Footprint" ""
				(at 0 0 0)
				(effects
					(font
						(size 1.27 1.27)
					)
					(hide yes)
				)
			)
			(property "Datasheet" ""
				(at 0 0 0)
				(effects
					(font
						(size 1.27 1.27)
					)
					(hide yes)
				)
			)
			(property "Description" ""
				(at 0 -6.35 0)
				(effects
					(font
						(size 1.27 1.27)
					)
					(justify left bottom)
					(hide yes)
				)
			)
			(symbol "+12V_0_1"
				(polyline
					(pts
						(xy -0.762 1.27) (xy 0 2.54)
					)
					(stroke
						(width 0)
						(type default)
					)
					(fill
						(type none)
					)
				)
				(polyline
					(pts
						(xy 0 2.54) (xy 0.762 1.27)
					)
					(stroke
						(width 0)
						(type default)
					)
					(fill
						(type none)
					)
				)
				(polyline
					(pts
						(xy 0 0) (xy 0 2.54)
					)
					(stroke
						(width 0)
						(type default)
					)
					(fill
						(type none)
					)
				)
			)
			(symbol "+12V_1_1"
				(pin power_in line
					(at 0 0 90)
					(length 0)
					(hide yes)
					(name "+12V"
						(effects
							(font
								(size 1.27 1.27)
							)
						)
					)
					(number "1"
						(effects
							(font
								(size 1.27 1.27)
							)
						)
					)
				)
			)
		)
	(symbol "antmicropower:+5V"
			(power)
			(pin_numbers
				(hide yes)
			)
			(pin_names
				(hide yes)
			)
			(exclude_from_sim no)
			(in_bom yes)
			(on_board yes)
			(property "Reference" "#PWR"
				(at 15.24 -2.54 0)
				(effects
					(font
						(size 1.27 1.27)
						(thickness 0.15)
					)
					(justify left bottom)
					(hide yes)
				)
			)
			(property "Value" "+5V"
				(at 15.24 -5.08 0)
				(effects
					(font
						(size 1.27 1.27)
						(thickness 0.15)
					)
					(justify left bottom)
				)
			)
			(property "Footprint" ""
				(at 15.24 -7.62 0)
				(effects
					(font
						(size 1.27 1.27)
						(thickness 0.15)
					)
					(justify left bottom)
					(hide yes)
				)
			)
			(property "Datasheet" ""
				(at 15.24 -10.16 0)
				(effects
					(font
						(size 1.27 1.27)
						(thickness 0.15)
					)
					(justify left bottom)
					(hide yes)
				)
			)
			(property "Description" ""
				(at 15.24 -12.7 0)
				(effects
					(font
						(size 1.27 1.27)
					)
					(justify left bottom)
					(hide yes)
				)
			)
			(property "Author" "Antmicro"
				(at 15.24 -7.62 0)
				(effects
					(font
						(size 1.27 1.27)
						(thickness 0.15)
					)
					(justify left bottom)
					(hide yes)
				)
			)
			(property "License" "Apache-2.0"
				(at 15.24 -10.16 0)
				(effects
					(font
						(size 1.27 1.27)
						(thickness 0.15)
					)
					(justify left bottom)
					(hide yes)
				)
			)
			(symbol "+5V_1_1"
				(polyline
					(pts
						(xy -0.762 1.27) (xy 0 2.54)
					)
					(stroke
						(width 0)
						(type default)
					)
					(fill
						(type background)
					)
				)
				(polyline
					(pts
						(xy 0 2.54) (xy 0.762 1.27)
					)
					(stroke
						(width 0)
						(type default)
					)
					(fill
						(type background)
					)
				)
				(polyline
					(pts
						(xy 0 0) (xy 0 2.54)
					)
					(stroke
						(width 0)
						(type default)
					)
					(fill
						(type background)
					)
				)
				(pin power_in line
					(at 0 0 90)
					(length 0)
					(name "+5V"
						(effects
							(font
								(size 1.27 1.27)
							)
						)
					)
					(number "1"
						(effects
							(font
								(size 1.27 1.27)
							)
						)
					)
				)
			)
		)
	(symbol "antmicropower:GND"
			(power)
			(pin_numbers
				(hide yes)
			)
			(pin_names
				(hide yes)
			)
			(exclude_from_sim no)
			(in_bom yes)
			(on_board yes)
			(property "Reference" "#PWR"
				(at 8.89 -2.54 0)
				(effects
					(font
						(size 1.27 1.27)
						(thickness 0.15)
					)
					(justify left bottom)
					(hide yes)
				)
			)
			(property "Value" "GND"
				(at 8.89 -5.08 0)
				(effects
					(font
						(size 1.27 1.27)
						(thickness 0.15)
					)
					(justify left bottom)
				)
			)
			(property "Footprint" ""
				(at 8.89 -7.62 0)
				(effects
					(font
						(size 1.27 1.27)
						(thickness 0.15)
					)
					(justify left bottom)
					(hide yes)
				)
			)
			(property "Datasheet" ""
				(at 8.89 -12.7 0)
				(effects
					(font
						(size 1.27 1.27)
						(thickness 0.15)
					)
					(justify left bottom)
					(hide yes)
				)
			)
			(property "Description" ""
				(at 8.89 -15.24 0)
				(effects
					(font
						(size 1.27 1.27)
					)
					(justify left bottom)
					(hide yes)
				)
			)
			(property "Author" "Antmicro"
				(at 8.89 -7.62 0)
				(effects
					(font
						(size 1.27 1.27)
						(thickness 0.15)
					)
					(justify left bottom)
					(hide yes)
				)
			)
			(property "License" "Apache-2.0"
				(at 8.89 -10.16 0)
				(effects
					(font
						(size 1.27 1.27)
						(thickness 0.15)
					)
					(justify left bottom)
					(hide yes)
				)
			)
			(symbol "GND_1_1"
				(polyline
					(pts
						(xy 0 0) (xy 0 -1.27) (xy 1.27 -1.27) (xy 0 -2.54) (xy -1.27 -1.27) (xy 0 -1.27)
					)
					(stroke
						(width 0)
						(type default)
					)
					(fill
						(type none)
					)
				)
				(pin power_in line
					(at 0 0 270)
					(length 0)
					(name "GND"
						(effects
							(font
								(size 1.27 1.27)
							)
						)
					)
					(number "1"
						(effects
							(font
								(size 1.27 1.27)
							)
						)
					)
				)
			)
		)
)
